(kicad_pcb
	(version 20260206)
	(generator "pcbnew")
	(generator_version "10.0")
	(general
		(thickness 1.6)
		(legacy_teardrops no)
	)
	(paper "A4")
	(title_block
		(title "12092022_DA0F0TFB6D0_F0T_FAN_BOARD_MP5048_D_brd_v02_OCP.brd")
		(comment 1 "Grand Teton / footprints 204-210 of 924")
	)
	(layers
		(0 "F.Cu" signal "TOP")
		(4 "In1.Cu" signal "GND")
		(6 "In2.Cu" signal "IN1")
		(8 "In3.Cu" signal "IN2")
		(10 "In4.Cu" signal "GND1")
		(2 "B.Cu" signal "BOTTOM")
		(9 "F.Adhes" user "F.Adhesive")
		(11 "B.Adhes" user "B.Adhesive")
		(13 "F.Paste" user "Package Geometry/Pastemask Top")
		(15 "B.Paste" user "Package Geometry/Pastemask Bottom")
		(5 "F.SilkS" user "Ref Des/Silkscreen Top")
		(7 "B.SilkS" user "Ref Des/Silkscreen Bottom")
		(1 "F.Mask" user "Board Geometry/Soldermask Top")
		(3 "B.Mask" user "Board Geometry/Soldermask Bottom")
		(17 "Dwgs.User" user "User.Drawings")
		(19 "Cmts.User" user "User.Comments")
		(21 "Eco1.User" user "User.Eco1")
		(23 "Eco2.User" user "User.Eco2")
		(25 "Edge.Cuts" user "Board Geometry/Outline")
		(27 "Margin" user)
		(31 "F.CrtYd" user "Package Geometry/Place Bound Top")
		(29 "B.CrtYd" user "Package Geometry/Place Bound Bottom")
		(35 "F.Fab" user "Ref Des/Assembly Top")
		(33 "B.Fab" user "Ref Des/Assembly Bottom")
	)
	(footprint ""
		(layer "F.Cu")
		(at 33.274 -160.02 90)
		(property "Reference" "R4874"
			(at 0 0 90)
			(layer "F.SilkS")
			(hide yes)
			(effects
				(font
					(size 1.27 1.27)
				)
			)
		)
		(property "Value" ""
			(at 0 0 90)
			(layer "F.Fab")
			(effects
				(font
					(size 1.27 1.27)
				)
			)
		)
		(duplicate_pad_numbers_are_jumpers no)
		(fp_line
			(start 0.7874 -0.4064)
			(end 0.7874 0.4064)
			(stroke
				(width 0.1524)
				(type default)
			)
			(layer "F.SilkS")
		)
		(fp_line
			(start -0.7874 -0.4064)
			(end 0.7874 -0.4064)
			(stroke
				(width 0.1524)
				(type default)
			)
			(layer "F.SilkS")
		)
		(fp_line
			(start 0.7874 0.4064)
			(end -0.7874 0.4064)
			(stroke
				(width 0.1524)
				(type default)
			)
			(layer "F.SilkS")
		)
		(fp_line
			(start -0.7874 0.4064)
			(end -0.7874 -0.4064)
			(stroke
				(width 0.1524)
				(type default)
			)
			(layer "F.SilkS")
		)
		(fp_line
			(start -0.12065 -0.305054)
			(end -0.12065 -0.2794)
			(stroke
				(width 0.1)
				(type default)
			)
			(layer "F.Fab")
		)
		(fp_line
			(start -0.67945 -0.305054)
			(end -0.12065 -0.305054)
			(stroke
				(width 0.1)
				(type default)
			)
			(layer "F.Fab")
		)
		(fp_line
			(start 0.67945 -0.3048)
			(end 0.67945 0.3048)
			(stroke
				(width 0.1)
				(type default)
			)
			(layer "F.Fab")
		)
		(fp_line
			(start 0.12065 -0.3048)
			(end 0.67945 -0.3048)
			(stroke
				(width 0.1)
				(type default)
			)
			(layer "F.Fab")
		)
		(fp_line
			(start 0.12065 -0.2794)
			(end 0.12065 -0.3048)
			(stroke
				(width 0.1)
				(type default)
			)
			(layer "F.Fab")
		)
		(fp_line
			(start -0.12065 -0.2794)
			(end 0.12065 -0.2794)
			(stroke
				(width 0.1)
				(type default)
			)
			(layer "F.Fab")
		)
		(fp_line
			(start 0.120396 0.2794)
			(end -0.12065 0.2794)
			(stroke
				(width 0.1)
				(type default)
			)
			(layer "F.Fab")
		)
		(fp_line
			(start -0.12065 0.2794)
			(end -0.12065 0.3048)
			(stroke
				(width 0.1)
				(type default)
			)
			(layer "F.Fab")
		)
		(fp_line
			(start 0.67945 0.3048)
			(end 0.120396 0.3048)
			(stroke
				(width 0.1)
				(type default)
			)
			(layer "F.Fab")
		)
		(fp_line
			(start 0.120396 0.3048)
			(end 0.120396 0.2794)
			(stroke
				(width 0.1)
				(type default)
			)
			(layer "F.Fab")
		)
		(fp_line
			(start -0.12065 0.3048)
			(end -0.67945 0.3048)
			(stroke
				(width 0.1)
				(type default)
			)
			(layer "F.Fab")
		)
		(fp_line
			(start -0.67945 0.3048)
			(end -0.67945 -0.305054)
			(stroke
				(width 0.1)
				(type default)
			)
			(layer "F.Fab")
		)
		(pad "1" smd circle
			(at -0.40005 0 90)
			(size 0 0)
			(layers "F.Cu" "F.Mask" "F.Paste")
			(net "SMB_FAN4_R_SCL")
		)
		(pad "2" smd circle
			(at 0.40005 0 90)
			(size 0 0)
			(layers "F.Cu" "F.Mask" "F.Paste")
			(net "SMB_FAN4_SCL")
		)
	)
	(footprint ""
		(layer "F.Cu")
		(at 25.781 -208.788 180)
		(property "Reference" "U63"
			(at 1.13538 1.98247 0)
			(unlocked yes)
			(layer "F.SilkS")
			(effects
				(font
					(size 0.7874 0.5842)
					(thickness 0.1524)
				)
				(justify left)
			)
		)
		(property "Value" ""
			(at 0 0 180)
			(layer "F.Fab")
			(effects
				(font
					(size 1.27 1.27)
				)
			)
		)
		(duplicate_pad_numbers_are_jumpers no)
		(fp_line
			(start 1.538478 1.150874)
			(end 1.538478 -1.150874)
			(stroke
				(width 0.1524)
				(type default)
			)
			(layer "F.SilkS")
		)
		(fp_line
			(start 1.538478 -1.150874)
			(end -1.538478 -1.150874)
			(stroke
				(width 0.1524)
				(type default)
			)
			(layer "F.SilkS")
		)
		(fp_line
			(start -1.538478 1.150874)
			(end 1.538478 1.150874)
			(stroke
				(width 0.1524)
				(type default)
			)
			(layer "F.SilkS")
		)
		(fp_line
			(start -1.538478 -1.150874)
			(end -1.538478 1.150874)
			(stroke
				(width 0.1524)
				(type default)
			)
			(layer "F.SilkS")
		)
		(fp_line
			(start 0.674878 1.100074)
			(end 0.674878 -1.100074)
			(stroke
				(width 0.1)
				(type default)
			)
			(layer "F.Fab")
		)
		(fp_line
			(start 0.674878 -1.100074)
			(end -0.674878 -1.100074)
			(stroke
				(width 0.1)
				(type default)
			)
			(layer "F.Fab")
		)
		(fp_line
			(start -0.674878 1.100074)
			(end 0.674878 1.100074)
			(stroke
				(width 0.1)
				(type default)
			)
			(layer "F.Fab")
		)
		(fp_line
			(start -0.674878 -1.100074)
			(end -0.674878 1.100074)
			(stroke
				(width 0.1)
				(type default)
			)
			(layer "F.Fab")
		)
		(pad "1" smd rect
			(at -0.94996 -0.649986 270)
			(size 0.7112 0.9144)
			(layers "F.Cu" "F.Mask" "F.Paste")
			(net "FAN_1_PWM_IL")
		)
		(pad "2" smd rect
			(at -0.94996 0.649986 270)
			(size 0.7112 0.9144)
			(layers "F.Cu" "F.Mask" "F.Paste")
			(net "FAN_1_PWM_OL")
		)
		(pad "3" smd rect
			(at 0.94996 0 270)
			(size 0.7112 0.9144)
			(layers "F.Cu" "F.Mask" "F.Paste")
			(net "FAN_1_PWM_BUF")
		)
	)
	(footprint ""
		(layer "F.Cu")
		(at 32.893 -15.113)
		(property "Reference" "R5325"
			(at 0 0 0)
			(layer "F.SilkS")
			(hide yes)
			(effects
				(font
					(size 1.27 1.27)
				)
			)
		)
		(property "Value" ""
			(at 0 0 0)
			(layer "F.Fab")
			(effects
				(font
					(size 1.27 1.27)
				)
			)
		)
		(duplicate_pad_numbers_are_jumpers no)
		(fp_line
			(start -1.2954 -0.5842)
			(end 1.2954 -0.5842)
			(stroke
				(width 0.1524)
				(type default)
			)
			(layer "F.SilkS")
		)
		(fp_line
			(start -1.2954 0.5842)
			(end -1.2954 -0.5842)
			(stroke
				(width 0.1524)
				(type default)
			)
			(layer "F.SilkS")
		)
		(fp_line
			(start 1.2954 -0.5842)
			(end 1.2954 0.5842)
			(stroke
				(width 0.1524)
				(type default)
			)
			(layer "F.SilkS")
		)
		(fp_line
			(start 1.2954 0.5842)
			(end -1.2954 0.5842)
			(stroke
				(width 0.1524)
				(type default)
			)
			(layer "F.SilkS")
		)
		(fp_line
			(start -1.1938 -0.406654)
			(end -0.8636 -0.406654)
			(stroke
				(width 0.1)
				(type default)
			)
			(layer "F.Fab")
		)
		(fp_line
			(start -1.1938 0.4064)
			(end -1.1938 -0.406654)
			(stroke
				(width 0.1)
				(type default)
			)
			(layer "F.Fab")
		)
		(fp_line
			(start -0.8636 -0.4572)
			(end 0.8636 -0.4572)
			(stroke
				(width 0.1)
				(type default)
			)
			(layer "F.Fab")
		)
		(fp_line
			(start -0.8636 -0.406654)
			(end -0.8636 -0.4572)
			(stroke
				(width 0.1)
				(type default)
			)
			(layer "F.Fab")
		)
		(fp_line
			(start -0.8636 0.4064)
			(end -1.1938 0.4064)
			(stroke
				(width 0.1)
				(type default)
			)
			(layer "F.Fab")
		)
		(fp_line
			(start -0.8636 0.4318)
			(end -0.8636 0.4064)
			(stroke
				(width 0.1)
				(type default)
			)
			(layer "F.Fab")
		)
		(fp_line
			(start -0.8636 0.4572)
			(end -0.8636 0.4318)
			(stroke
				(width 0.1)
				(type default)
			)
			(layer "F.Fab")
		)
		(fp_line
			(start 0.8636 -0.4572)
			(end 0.8636 -0.406654)
			(stroke
				(width 0.1)
				(type default)
			)
			(layer "F.Fab")
		)
		(fp_line
			(start 0.8636 -0.406654)
			(end 1.1938 -0.406654)
			(stroke
				(width 0.1)
				(type default)
			)
			(layer "F.Fab")
		)
		(fp_line
			(start 0.8636 0.4064)
			(end 0.8636 0.4572)
			(stroke
				(width 0.1)
				(type default)
			)
			(layer "F.Fab")
		)
		(fp_line
			(start 0.8636 0.4572)
			(end -0.8636 0.4572)
			(stroke
				(width 0.1)
				(type default)
			)
			(layer "F.Fab")
		)
		(fp_line
			(start 1.1938 -0.406654)
			(end 1.1938 0.4064)
			(stroke
				(width 0.1)
				(type default)
			)
			(layer "F.Fab")
		)
		(fp_line
			(start 1.1938 0.4064)
			(end 0.8636 0.4064)
			(stroke
				(width 0.1)
				(type default)
			)
			(layer "F.Fab")
		)
		(pad "1" smd rect
			(at -0.7366 0 270)
			(size 0.7112 0.8128)
			(layers "F.Cu" "F.Mask" "F.Paste")
			(net "P52V_FAN_3")
		)
		(pad "2" smd rect
			(at 0.7366 0 270)
			(size 0.7112 0.8128)
			(layers "F.Cu" "F.Mask" "F.Paste")
			(net "FAN_3_TACH_OL_R")
		)
	)
	(footprint ""
		(layer "F.Cu")
		(at 26.945336 -20.713954 180)
		(property "Reference" "R5515"
			(at 0 0 180)
			(layer "F.SilkS")
			(hide yes)
			(effects
				(font
					(size 1.27 1.27)
				)
			)
		)
		(property "Value" ""
			(at 0 0 180)
			(layer "F.Fab")
			(effects
				(font
					(size 1.27 1.27)
				)
			)
		)
		(duplicate_pad_numbers_are_jumpers no)
		(fp_line
			(start 0.7874 0.4064)
			(end -0.7874 0.4064)
			(stroke
				(width 0.1524)
				(type default)
			)
			(layer "F.SilkS")
		)
		(fp_line
			(start 0.7874 -0.4064)
			(end 0.7874 0.4064)
			(stroke
				(width 0.1524)
				(type default)
			)
			(layer "F.SilkS")
		)
		(fp_line
			(start -0.7874 0.4064)
			(end -0.7874 -0.4064)
			(stroke
				(width 0.1524)
				(type default)
			)
			(layer "F.SilkS")
		)
		(fp_line
			(start -0.7874 -0.4064)
			(end 0.7874 -0.4064)
			(stroke
				(width 0.1524)
				(type default)
			)
			(layer "F.SilkS")
		)
		(fp_line
			(start 0.67945 0.3048)
			(end 0.120396 0.3048)
			(stroke
				(width 0.1)
				(type default)
			)
			(layer "F.Fab")
		)
		(fp_line
			(start 0.67945 -0.3048)
			(end 0.67945 0.3048)
			(stroke
				(width 0.1)
				(type default)
			)
			(layer "F.Fab")
		)
		(fp_line
			(start 0.12065 -0.2794)
			(end 0.12065 -0.3048)
			(stroke
				(width 0.1)
				(type default)
			)
			(layer "F.Fab")
		)
		(fp_line
			(start 0.12065 -0.3048)
			(end 0.67945 -0.3048)
			(stroke
				(width 0.1)
				(type default)
			)
			(layer "F.Fab")
		)
		(fp_line
			(start 0.120396 0.3048)
			(end 0.120396 0.2794)
			(stroke
				(width 0.1)
				(type default)
			)
			(layer "F.Fab")
		)
		(fp_line
			(start 0.120396 0.2794)
			(end -0.12065 0.2794)
			(stroke
				(width 0.1)
				(type default)
			)
			(layer "F.Fab")
		)
		(fp_line
			(start -0.12065 0.3048)
			(end -0.67945 0.3048)
			(stroke
				(width 0.1)
				(type default)
			)
			(layer "F.Fab")
		)
		(fp_line
			(start -0.12065 0.2794)
			(end -0.12065 0.3048)
			(stroke
				(width 0.1)
				(type default)
			)
			(layer "F.Fab")
		)
		(fp_line
			(start -0.12065 -0.2794)
			(end 0.12065 -0.2794)
			(stroke
				(width 0.1)
				(type default)
			)
			(layer "F.Fab")
		)
		(fp_line
			(start -0.12065 -0.305054)
			(end -0.12065 -0.2794)
			(stroke
				(width 0.1)
				(type default)
			)
			(layer "F.Fab")
		)
		(fp_line
			(start -0.67945 0.3048)
			(end -0.67945 -0.305054)
			(stroke
				(width 0.1)
				(type default)
			)
			(layer "F.Fab")
		)
		(fp_line
			(start -0.67945 -0.305054)
			(end -0.12065 -0.305054)
			(stroke
				(width 0.1)
				(type default)
			)
			(layer "F.Fab")
		)
		(pad "1" smd circle
			(at -0.40005 0 180)
			(size 0 0)
			(layers "F.Cu" "F.Mask" "F.Paste")
			(net "P3V3_AUX")
		)
		(pad "2" smd circle
			(at 0.40005 0 180)
			(size 0 0)
			(layers "F.Cu" "F.Mask" "F.Paste")
			(net "FAN_4_PWM_BUF")
		)
	)
	(footprint ""
		(layer "F.Cu")
		(at 32.258 -203.962 90)
		(property "Reference" "R5527"
			(at 0 0 90)
			(layer "F.SilkS")
			(hide yes)
			(effects
				(font
					(size 1.27 1.27)
				)
			)
		)
		(property "Value" ""
			(at 0 0 90)
			(layer "F.Fab")
			(effects
				(font
					(size 1.27 1.27)
				)
			)
		)
		(duplicate_pad_numbers_are_jumpers no)
		(fp_line
			(start 0.7874 -0.4064)
			(end 0.7874 0.4064)
			(stroke
				(width 0.1524)
				(type default)
			)
			(layer "F.SilkS")
		)
		(fp_line
			(start -0.7874 -0.4064)
			(end 0.7874 -0.4064)
			(stroke
				(width 0.1524)
				(type default)
			)
			(layer "F.SilkS")
		)
		(fp_line
			(start 0.7874 0.4064)
			(end -0.7874 0.4064)
			(stroke
				(width 0.1524)
				(type default)
			)
			(layer "F.SilkS")
		)
		(fp_line
			(start -0.7874 0.4064)
			(end -0.7874 -0.4064)
			(stroke
				(width 0.1524)
				(type default)
			)
			(layer "F.SilkS")
		)
		(fp_line
			(start -0.12065 -0.305054)
			(end -0.12065 -0.2794)
			(stroke
				(width 0.1)
				(type default)
			)
			(layer "F.Fab")
		)
		(fp_line
			(start -0.67945 -0.305054)
			(end -0.12065 -0.305054)
			(stroke
				(width 0.1)
				(type default)
			)
			(layer "F.Fab")
		)
		(fp_line
			(start 0.67945 -0.3048)
			(end 0.67945 0.3048)
			(stroke
				(width 0.1)
				(type default)
			)
			(layer "F.Fab")
		)
		(fp_line
			(start 0.12065 -0.3048)
			(end 0.67945 -0.3048)
			(stroke
				(width 0.1)
				(type default)
			)
			(layer "F.Fab")
		)
		(fp_line
			(start 0.12065 -0.2794)
			(end 0.12065 -0.3048)
			(stroke
				(width 0.1)
				(type default)
			)
			(layer "F.Fab")
		)
		(fp_line
			(start -0.12065 -0.2794)
			(end 0.12065 -0.2794)
			(stroke
				(width 0.1)
				(type default)
			)
			(layer "F.Fab")
		)
		(fp_line
			(start 0.120396 0.2794)
			(end -0.12065 0.2794)
			(stroke
				(width 0.1)
				(type default)
			)
			(layer "F.Fab")
		)
		(fp_line
			(start -0.12065 0.2794)
			(end -0.12065 0.3048)
			(stroke
				(width 0.1)
				(type default)
			)
			(layer "F.Fab")
		)
		(fp_line
			(start 0.67945 0.3048)
			(end 0.120396 0.3048)
			(stroke
				(width 0.1)
				(type default)
			)
			(layer "F.Fab")
		)
		(fp_line
			(start 0.120396 0.3048)
			(end 0.120396 0.2794)
			(stroke
				(width 0.1)
				(type default)
			)
			(layer "F.Fab")
		)
		(fp_line
			(start -0.12065 0.3048)
			(end -0.67945 0.3048)
			(stroke
				(width 0.1)
				(type default)
			)
			(layer "F.Fab")
		)
		(fp_line
			(start -0.67945 0.3048)
			(end -0.67945 -0.305054)
			(stroke
				(width 0.1)
				(type default)
			)
			(layer "F.Fab")
		)
		(pad "1" smd rect
			(at -0.40005 0 270)
			(size 0.4572 0.508)
			(layers "F.Cu" "F.Mask" "F.Paste")
			(net "P12V_LED_FAN1")
		)
		(pad "2" smd rect
			(at 0.40005 0 270)
			(size 0.4572 0.508)
			(layers "F.Cu" "F.Mask" "F.Paste")
			(net "FAN_1_FAIL_LED_R_N")
		)
	)
	(footprint ""
		(layer "F.Cu")
		(at 21.336 -215.519 180)
		(property "Reference" "U411"
			(at 1.40462 -1.83515 0)
			(unlocked yes)
			(layer "F.SilkS")
			(effects
				(font
					(size 0.7874 0.5842)
					(thickness 0.1524)
				)
				(justify left)
			)
		)
		(property "Value" ""
			(at 0 0 180)
			(layer "F.Fab")
			(effects
				(font
					(size 1.27 1.27)
				)
			)
		)
		(duplicate_pad_numbers_are_jumpers no)
		(fp_line
			(start 1.335278 1.100074)
			(end 1.335278 -1.100074)
			(stroke
				(width 0.1524)
				(type default)
			)
			(layer "F.SilkS")
		)
		(fp_line
			(start 1.335278 -1.100074)
			(end -1.335278 -1.100074)
			(stroke
				(width 0.1524)
				(type default)
			)
			(layer "F.SilkS")
		)
		(fp_line
			(start -1.335278 1.100074)
			(end 1.335278 1.100074)
			(stroke
				(width 0.1524)
				(type default)
			)
			(layer "F.SilkS")
		)
		(fp_line
			(start -1.335278 -1.100074)
			(end -1.335278 1.100074)
			(stroke
				(width 0.1524)
				(type default)
			)
			(layer "F.SilkS")
		)
		(fp_line
			(start 0.674878 1.100074)
			(end 0.674878 -1.100074)
			(stroke
				(width 0.1)
				(type default)
			)
			(layer "F.Fab")
		)
		(fp_line
			(start 0.674878 -1.100074)
			(end -0.674878 -1.100074)
			(stroke
				(width 0.1)
				(type default)
			)
			(layer "F.Fab")
		)
		(fp_line
			(start -0.674878 1.100074)
			(end 0.674878 1.100074)
			(stroke
				(width 0.1)
				(type default)
			)
			(layer "F.Fab")
		)
		(fp_line
			(start -0.674878 -1.100074)
			(end -0.674878 1.100074)
			(stroke
				(width 0.1)
				(type default)
			)
			(layer "F.Fab")
		)
		(pad "D" smd rect
			(at 0.8001 0 90)
			(size 0.6096 0.8128)
			(layers "F.Cu" "F.Mask" "F.Paste")
			(net "U411_D1")
		)
		(pad "G" smd rect
			(at -0.8001 -0.649986 90)
			(size 0.6096 0.8128)
			(layers "F.Cu" "F.Mask" "F.Paste")
			(net "FAN_6_PRESENT")
		)
		(pad "S" smd rect
			(at -0.8001 0.649986 90)
			(size 0.6096 0.8128)
			(layers "F.Cu" "F.Mask" "F.Paste")
			(net "GND")
		)
	)
	(footprint ""
		(layer "F.Cu")
		(at 32.893 -29.972 180)
		(property "Reference" "C2054"
			(at 0 0 180)
			(layer "F.SilkS")
			(hide yes)
			(effects
				(font
					(size 1.27 1.27)
				)
			)
		)
		(property "Value" ""
			(at 0 0 180)
			(layer "F.Fab")
			(effects
				(font
					(size 1.27 1.27)
				)
			)
		)
		(duplicate_pad_numbers_are_jumpers no)
		(fp_line
			(start 0.7874 0.4064)
			(end -0.7874 0.4064)
			(stroke
				(width 0.1524)
				(type default)
			)
			(layer "F.SilkS")
		)
		(fp_line
			(start 0.7874 -0.4064)
			(end 0.7874 0.4064)
			(stroke
				(width 0.1524)
				(type default)
			)
			(layer "F.SilkS")
		)
		(fp_line
			(start -0.7874 0.4064)
			(end -0.7874 -0.4064)
			(stroke
				(width 0.1524)
				(type default)
			)
			(layer "F.SilkS")
		)
		(fp_line
			(start -0.7874 -0.4064)
			(end 0.7874 -0.4064)
			(stroke
				(width 0.1524)
				(type default)
			)
			(layer "F.SilkS")
		)
		(fp_line
			(start 0.67945 0.3048)
			(end 0.120396 0.3048)
			(stroke
				(width 0.1)
				(type default)
			)
			(layer "F.Fab")
		)
		(fp_line
			(start 0.67945 -0.3048)
			(end 0.67945 0.3048)
			(stroke
				(width 0.1)
				(type default)
			)
			(layer "F.Fab")
		)
		(fp_line
			(start 0.12065 -0.2794)
			(end 0.12065 -0.3048)
			(stroke
				(width 0.1)
				(type default)
			)
			(layer "F.Fab")
		)
		(fp_line
			(start 0.12065 -0.3048)
			(end 0.67945 -0.3048)
			(stroke
				(width 0.1)
				(type default)
			)
			(layer "F.Fab")
		)
		(fp_line
			(start 0.120396 0.3048)
			(end 0.120396 0.2794)
			(stroke
				(width 0.1)
				(type default)
			)
			(layer "F.Fab")
		)
		(fp_line
			(start 0.120396 0.2794)
			(end -0.12065 0.2794)
			(stroke
				(width 0.1)
				(type default)
			)
			(layer "F.Fab")
		)
		(fp_line
			(start -0.12065 0.3048)
			(end -0.67945 0.3048)
			(stroke
				(width 0.1)
				(type default)
			)
			(layer "F.Fab")
		)
		(fp_line
			(start -0.12065 0.2794)
			(end -0.12065 0.3048)
			(stroke
				(width 0.1)
				(type default)
			)
			(layer "F.Fab")
		)
		(fp_line
			(start -0.12065 -0.2794)
			(end 0.12065 -0.2794)
			(stroke
				(width 0.1)
				(type default)
			)
			(layer "F.Fab")
		)
		(fp_line
			(start -0.12065 -0.305054)
			(end -0.12065 -0.2794)
			(stroke
				(width 0.1)
				(type default)
			)
			(layer "F.Fab")
		)
		(fp_line
			(start -0.67945 0.3048)
			(end -0.67945 -0.305054)
			(stroke
				(width 0.1)
				(type default)
			)
			(layer "F.Fab")
		)
		(fp_line
			(start -0.67945 -0.305054)
			(end -0.12065 -0.305054)
			(stroke
				(width 0.1)
				(type default)
			)
			(layer "F.Fab")
		)
		(pad "1" smd circle
			(at -0.40005 0 180)
			(size 0 0)
			(layers "F.Cu" "F.Mask" "F.Paste")
			(net "FAN_3_TACH_IL_R")
		)
		(pad "2" smd circle
			(at 0.40005 0 180)
			(size 0 0)
			(layers "F.Cu" "F.Mask" "F.Paste")
			(net "GND")
		)
	)
)
